(kicad_pcb
	(version 20260206)
	(generator "pcbnew")
	(generator_version "10.0")
	(general
		(thickness 1.6)
		(legacy_teardrops no)
	)
	(paper "A4")
	(title_block
		(title "01162023_DA0F0TEBIF0_F0T_Expander_BD_F_brd_V02_OCP.brd")
		(comment 1 "Grand Teton / footprints 4899-4904 of 9728")
	)
	(layers
		(0 "F.Cu" signal "TOP")
		(4 "In1.Cu" signal "GND")
		(6 "In2.Cu" signal "VCC")
		(8 "In3.Cu" signal "VCC1")
		(10 "In4.Cu" signal "GND1")
		(12 "In5.Cu" signal "IN1")
		(14 "In6.Cu" signal "GND2")
		(16 "In7.Cu" signal "IN2")
		(18 "In8.Cu" signal "GND3")
		(20 "In9.Cu" signal "IN3")
		(22 "In10.Cu" signal "GND4")
		(24 "In11.Cu" signal "IN4")
		(26 "In12.Cu" signal "GND5")
		(28 "In13.Cu" signal "IN5")
		(30 "In14.Cu" signal "GND6")
		(32 "In15.Cu" signal "IN6")
		(34 "In16.Cu" signal "GND7")
		(2 "B.Cu" signal "BOTTOM")
		(9 "F.Adhes" user "F.Adhesive")
		(11 "B.Adhes" user "B.Adhesive")
		(13 "F.Paste" user "Package Geometry/Pastemask Top")
		(15 "B.Paste" user "Package Geometry/Pastemask Bottom")
		(5 "F.SilkS" user "Ref Des/Silkscreen Top")
		(7 "B.SilkS" user "Ref Des/Silkscreen Bottom")
		(1 "F.Mask" user "Board Geometry/Soldermask Top")
		(3 "B.Mask" user "Board Geometry/Soldermask Bottom")
		(17 "Dwgs.User" user "User.Drawings")
		(19 "Cmts.User" user "User.Comments")
		(21 "Eco1.User" user "User.Eco1")
		(23 "Eco2.User" user "User.Eco2")
		(25 "Edge.Cuts" user "Board Geometry/Outline")
		(27 "Margin" user)
		(31 "F.CrtYd" user "Package Geometry/Place Bound Top")
		(29 "B.CrtYd" user "Package Geometry/Place Bound Bottom")
		(35 "F.Fab" user "Ref Des/Assembly Top")
		(33 "B.Fab" user "Ref Des/Assembly Bottom")
	)
	(footprint ""
		(layer "F.Cu")
		(at 221.990158 -84.675472)
		(property "Reference" "R5769"
			(at 0 0 0)
			(layer "F.SilkS")
			(hide yes)
			(effects
				(font
					(size 1.27 1.27)
				)
			)
		)
		(property "Value" ""
			(at 0 0 0)
			(layer "F.Fab")
			(effects
				(font
					(size 1.27 1.27)
				)
			)
		)
		(duplicate_pad_numbers_are_jumpers no)
		(fp_line
			(start -0.7874 -0.4064)
			(end 0.7874 -0.4064)
			(stroke
				(width 0.1524)
				(type default)
			)
			(layer "F.SilkS")
		)
		(fp_line
			(start -0.7874 0.4064)
			(end -0.7874 -0.4064)
			(stroke
				(width 0.1524)
				(type default)
			)
			(layer "F.SilkS")
		)
		(fp_line
			(start 0.7874 -0.4064)
			(end 0.7874 0.4064)
			(stroke
				(width 0.1524)
				(type default)
			)
			(layer "F.SilkS")
		)
		(fp_line
			(start 0.7874 0.4064)
			(end -0.7874 0.4064)
			(stroke
				(width 0.1524)
				(type default)
			)
			(layer "F.SilkS")
		)
		(fp_line
			(start -0.67945 -0.305054)
			(end -0.12065 -0.305054)
			(stroke
				(width 0.1)
				(type default)
			)
			(layer "F.Fab")
		)
		(fp_line
			(start -0.67945 0.3048)
			(end -0.67945 -0.305054)
			(stroke
				(width 0.1)
				(type default)
			)
			(layer "F.Fab")
		)
		(fp_line
			(start -0.12065 -0.305054)
			(end -0.12065 -0.2794)
			(stroke
				(width 0.1)
				(type default)
			)
			(layer "F.Fab")
		)
		(fp_line
			(start -0.12065 -0.2794)
			(end 0.12065 -0.2794)
			(stroke
				(width 0.1)
				(type default)
			)
			(layer "F.Fab")
		)
		(fp_line
			(start -0.12065 0.2794)
			(end -0.12065 0.3048)
			(stroke
				(width 0.1)
				(type default)
			)
			(layer "F.Fab")
		)
		(fp_line
			(start -0.12065 0.3048)
			(end -0.67945 0.3048)
			(stroke
				(width 0.1)
				(type default)
			)
			(layer "F.Fab")
		)
		(fp_line
			(start 0.120396 0.2794)
			(end -0.12065 0.2794)
			(stroke
				(width 0.1)
				(type default)
			)
			(layer "F.Fab")
		)
		(fp_line
			(start 0.120396 0.3048)
			(end 0.120396 0.2794)
			(stroke
				(width 0.1)
				(type default)
			)
			(layer "F.Fab")
		)
		(fp_line
			(start 0.12065 -0.3048)
			(end 0.67945 -0.3048)
			(stroke
				(width 0.1)
				(type default)
			)
			(layer "F.Fab")
		)
		(fp_line
			(start 0.12065 -0.2794)
			(end 0.12065 -0.3048)
			(stroke
				(width 0.1)
				(type default)
			)
			(layer "F.Fab")
		)
		(fp_line
			(start 0.67945 -0.3048)
			(end 0.67945 0.3048)
			(stroke
				(width 0.1)
				(type default)
			)
			(layer "F.Fab")
		)
		(fp_line
			(start 0.67945 0.3048)
			(end 0.120396 0.3048)
			(stroke
				(width 0.1)
				(type default)
			)
			(layer "F.Fab")
		)
		(pad "1" smd circle
			(at -0.40005 0)
			(size 0 0)
			(layers "F.Cu" "F.Mask" "F.Paste")
			(net "SSD15_LED")
		)
		(pad "2" smd circle
			(at 0.40005 0)
			(size 0 0)
			(layers "F.Cu" "F.Mask" "F.Paste")
			(net "SSD15_LED_R")
		)
	)
	(footprint ""
		(layer "F.Cu")
		(at 293.74719 -195.362068 -90)
		(property "Reference" "R3393"
			(at 0 0 270)
			(layer "F.SilkS")
			(hide yes)
			(effects
				(font
					(size 1.27 1.27)
				)
			)
		)
		(property "Value" ""
			(at 0 0 270)
			(layer "F.Fab")
			(effects
				(font
					(size 1.27 1.27)
				)
			)
		)
		(duplicate_pad_numbers_are_jumpers no)
		(fp_line
			(start -0.7874 0.4064)
			(end -0.7874 -0.4064)
			(stroke
				(width 0.1524)
				(type default)
			)
			(layer "F.SilkS")
		)
		(fp_line
			(start 0.7874 0.4064)
			(end -0.7874 0.4064)
			(stroke
				(width 0.1524)
				(type default)
			)
			(layer "F.SilkS")
		)
		(fp_line
			(start -0.7874 -0.4064)
			(end 0.7874 -0.4064)
			(stroke
				(width 0.1524)
				(type default)
			)
			(layer "F.SilkS")
		)
		(fp_line
			(start 0.7874 -0.4064)
			(end 0.7874 0.4064)
			(stroke
				(width 0.1524)
				(type default)
			)
			(layer "F.SilkS")
		)
		(fp_line
			(start -0.67945 0.3048)
			(end -0.67945 -0.305054)
			(stroke
				(width 0.1)
				(type default)
			)
			(layer "F.Fab")
		)
		(fp_line
			(start -0.12065 0.3048)
			(end -0.67945 0.3048)
			(stroke
				(width 0.1)
				(type default)
			)
			(layer "F.Fab")
		)
		(fp_line
			(start 0.120396 0.3048)
			(end 0.120396 0.2794)
			(stroke
				(width 0.1)
				(type default)
			)
			(layer "F.Fab")
		)
		(fp_line
			(start 0.67945 0.3048)
			(end 0.120396 0.3048)
			(stroke
				(width 0.1)
				(type default)
			)
			(layer "F.Fab")
		)
		(fp_line
			(start -0.12065 0.2794)
			(end -0.12065 0.3048)
			(stroke
				(width 0.1)
				(type default)
			)
			(layer "F.Fab")
		)
		(fp_line
			(start 0.120396 0.2794)
			(end -0.12065 0.2794)
			(stroke
				(width 0.1)
				(type default)
			)
			(layer "F.Fab")
		)
		(fp_line
			(start -0.12065 -0.2794)
			(end 0.12065 -0.2794)
			(stroke
				(width 0.1)
				(type default)
			)
			(layer "F.Fab")
		)
		(fp_line
			(start 0.12065 -0.2794)
			(end 0.12065 -0.3048)
			(stroke
				(width 0.1)
				(type default)
			)
			(layer "F.Fab")
		)
		(fp_line
			(start 0.12065 -0.3048)
			(end 0.67945 -0.3048)
			(stroke
				(width 0.1)
				(type default)
			)
			(layer "F.Fab")
		)
		(fp_line
			(start 0.67945 -0.3048)
			(end 0.67945 0.3048)
			(stroke
				(width 0.1)
				(type default)
			)
			(layer "F.Fab")
		)
		(fp_line
			(start -0.67945 -0.305054)
			(end -0.12065 -0.305054)
			(stroke
				(width 0.1)
				(type default)
			)
			(layer "F.Fab")
		)
		(fp_line
			(start -0.12065 -0.305054)
			(end -0.12065 -0.2794)
			(stroke
				(width 0.1)
				(type default)
			)
			(layer "F.Fab")
		)
		(pad "1" smd circle
			(at -0.40005 0 270)
			(size 0 0)
			(layers "F.Cu" "F.Mask" "F.Paste")
			(net "SPI_BIC1_MISO_R4")
		)
		(pad "2" smd circle
			(at 0.40005 0 270)
			(size 0 0)
			(layers "F.Cu" "F.Mask" "F.Paste")
			(net "SPI_BIC1_MISO_R2")
		)
	)
	(footprint ""
		(layer "F.Cu")
		(at 233.25963 -77.36459 180)
		(property "Reference" "R1005"
			(at 0 0 180)
			(layer "F.SilkS")
			(hide yes)
			(effects
				(font
					(size 1.27 1.27)
				)
			)
		)
		(property "Value" ""
			(at 0 0 180)
			(layer "F.Fab")
			(effects
				(font
					(size 1.27 1.27)
				)
			)
		)
		(duplicate_pad_numbers_are_jumpers no)
		(fp_line
			(start 0.7874 0.4064)
			(end -0.7874 0.4064)
			(stroke
				(width 0.1524)
				(type default)
			)
			(layer "F.SilkS")
		)
		(fp_line
			(start 0.7874 -0.4064)
			(end 0.7874 0.4064)
			(stroke
				(width 0.1524)
				(type default)
			)
			(layer "F.SilkS")
		)
		(fp_line
			(start -0.7874 0.4064)
			(end -0.7874 -0.4064)
			(stroke
				(width 0.1524)
				(type default)
			)
			(layer "F.SilkS")
		)
		(fp_line
			(start -0.7874 -0.4064)
			(end 0.7874 -0.4064)
			(stroke
				(width 0.1524)
				(type default)
			)
			(layer "F.SilkS")
		)
		(fp_line
			(start 0.67945 0.3048)
			(end 0.120396 0.3048)
			(stroke
				(width 0.1)
				(type default)
			)
			(layer "F.Fab")
		)
		(fp_line
			(start 0.67945 -0.3048)
			(end 0.67945 0.3048)
			(stroke
				(width 0.1)
				(type default)
			)
			(layer "F.Fab")
		)
		(fp_line
			(start 0.12065 -0.2794)
			(end 0.12065 -0.3048)
			(stroke
				(width 0.1)
				(type default)
			)
			(layer "F.Fab")
		)
		(fp_line
			(start 0.12065 -0.3048)
			(end 0.67945 -0.3048)
			(stroke
				(width 0.1)
				(type default)
			)
			(layer "F.Fab")
		)
		(fp_line
			(start 0.120396 0.3048)
			(end 0.120396 0.2794)
			(stroke
				(width 0.1)
				(type default)
			)
			(layer "F.Fab")
		)
		(fp_line
			(start 0.120396 0.2794)
			(end -0.12065 0.2794)
			(stroke
				(width 0.1)
				(type default)
			)
			(layer "F.Fab")
		)
		(fp_line
			(start -0.12065 0.3048)
			(end -0.67945 0.3048)
			(stroke
				(width 0.1)
				(type default)
			)
			(layer "F.Fab")
		)
		(fp_line
			(start -0.12065 0.2794)
			(end -0.12065 0.3048)
			(stroke
				(width 0.1)
				(type default)
			)
			(layer "F.Fab")
		)
		(fp_line
			(start -0.12065 -0.2794)
			(end 0.12065 -0.2794)
			(stroke
				(width 0.1)
				(type default)
			)
			(layer "F.Fab")
		)
		(fp_line
			(start -0.12065 -0.305054)
			(end -0.12065 -0.2794)
			(stroke
				(width 0.1)
				(type default)
			)
			(layer "F.Fab")
		)
		(fp_line
			(start -0.67945 0.3048)
			(end -0.67945 -0.305054)
			(stroke
				(width 0.1)
				(type default)
			)
			(layer "F.Fab")
		)
		(fp_line
			(start -0.67945 -0.305054)
			(end -0.12065 -0.305054)
			(stroke
				(width 0.1)
				(type default)
			)
			(layer "F.Fab")
		)
		(pad "1" smd circle
			(at -0.40005 0 180)
			(size 0 0)
			(layers "F.Cu" "F.Mask" "F.Paste")
			(net "PWRGD_P3V3_AUX_MUX_N")
		)
		(pad "2" smd circle
			(at 0.40005 0 180)
			(size 0 0)
			(layers "F.Cu" "F.Mask" "F.Paste")
			(net "PWRGD_P3V3_AUX_MUX_R_N")
		)
	)
	(footprint ""
		(layer "F.Cu")
		(at 258.605274 -258.582922 90)
		(property "Reference" "L129"
			(at 0 0 90)
			(layer "F.SilkS")
			(hide yes)
			(effects
				(font
					(size 1.27 1.27)
				)
			)
		)
		(property "Value" ""
			(at 0 0 90)
			(layer "F.Fab")
			(effects
				(font
					(size 1.27 1.27)
				)
			)
		)
		(duplicate_pad_numbers_are_jumpers no)
		(fp_line
			(start 1.63576 -0.8128)
			(end 1.63576 0.8128)
			(stroke
				(width 0.1524)
				(type default)
			)
			(layer "F.SilkS")
		)
		(fp_line
			(start -1.63576 -0.8128)
			(end 1.63576 -0.8128)
			(stroke
				(width 0.1524)
				(type default)
			)
			(layer "F.SilkS")
		)
		(fp_line
			(start -1.63576 -0.8128)
			(end -1.63576 0.8128)
			(stroke
				(width 0.1524)
				(type default)
			)
			(layer "F.SilkS")
		)
		(fp_line
			(start 1.63576 0.8128)
			(end -1.63576 0.8128)
			(stroke
				(width 0.1524)
				(type default)
			)
			(layer "F.SilkS")
		)
		(fp_line
			(start 1.560576 -0.738632)
			(end -1.56083 -0.738632)
			(stroke
				(width 0.1)
				(type default)
			)
			(layer "F.Fab")
		)
		(fp_line
			(start -1.56083 -0.738632)
			(end -1.56083 0.7366)
			(stroke
				(width 0.1)
				(type default)
			)
			(layer "F.Fab")
		)
		(fp_line
			(start 1.560576 0.7366)
			(end 1.560576 -0.738632)
			(stroke
				(width 0.1)
				(type default)
			)
			(layer "F.Fab")
		)
		(fp_line
			(start 1.524 0.7366)
			(end 1.560576 0.7366)
			(stroke
				(width 0.1)
				(type default)
			)
			(layer "F.Fab")
		)
		(fp_line
			(start -1.524 0.7366)
			(end 1.524 0.7366)
			(stroke
				(width 0.1)
				(type default)
			)
			(layer "F.Fab")
		)
		(fp_line
			(start -1.56083 0.7366)
			(end -1.524 0.7366)
			(stroke
				(width 0.1)
				(type default)
			)
			(layer "F.Fab")
		)
		(pad "1" smd rect
			(at -0.94996 0 270)
			(size 1.1176 1.3716)
			(layers "F.Cu" "F.Mask" "F.Paste")
			(net "P1V8_PLL0_PEX2")
		)
		(pad "2" smd rect
			(at 0.94996 0 270)
			(size 1.1176 1.3716)
			(layers "F.Cu" "F.Mask" "F.Paste")
			(net "P1V8_VDDA_PEX2")
		)
	)
	(footprint ""
		(layer "F.Cu")
		(at 248.004838 -119.140986 -90)
		(property "Reference" "R6030"
			(at 0 0 270)
			(layer "F.SilkS")
			(hide yes)
			(effects
				(font
					(size 1.27 1.27)
				)
			)
		)
		(property "Value" ""
			(at 0 0 270)
			(layer "F.Fab")
			(effects
				(font
					(size 1.27 1.27)
				)
			)
		)
		(duplicate_pad_numbers_are_jumpers no)
		(fp_line
			(start -0.7874 0.4064)
			(end -0.7874 -0.4064)
			(stroke
				(width 0.1524)
				(type default)
			)
			(layer "F.SilkS")
		)
		(fp_line
			(start 0.7874 0.4064)
			(end -0.7874 0.4064)
			(stroke
				(width 0.1524)
				(type default)
			)
			(layer "F.SilkS")
		)
		(fp_line
			(start -0.7874 -0.4064)
			(end 0.7874 -0.4064)
			(stroke
				(width 0.1524)
				(type default)
			)
			(layer "F.SilkS")
		)
		(fp_line
			(start 0.7874 -0.4064)
			(end 0.7874 0.4064)
			(stroke
				(width 0.1524)
				(type default)
			)
			(layer "F.SilkS")
		)
		(fp_line
			(start -0.67945 0.3048)
			(end -0.67945 -0.305054)
			(stroke
				(width 0.1)
				(type default)
			)
			(layer "F.Fab")
		)
		(fp_line
			(start -0.12065 0.3048)
			(end -0.67945 0.3048)
			(stroke
				(width 0.1)
				(type default)
			)
			(layer "F.Fab")
		)
		(fp_line
			(start 0.120396 0.3048)
			(end 0.120396 0.2794)
			(stroke
				(width 0.1)
				(type default)
			)
			(layer "F.Fab")
		)
		(fp_line
			(start 0.67945 0.3048)
			(end 0.120396 0.3048)
			(stroke
				(width 0.1)
				(type default)
			)
			(layer "F.Fab")
		)
		(fp_line
			(start -0.12065 0.2794)
			(end -0.12065 0.3048)
			(stroke
				(width 0.1)
				(type default)
			)
			(layer "F.Fab")
		)
		(fp_line
			(start 0.120396 0.2794)
			(end -0.12065 0.2794)
			(stroke
				(width 0.1)
				(type default)
			)
			(layer "F.Fab")
		)
		(fp_line
			(start -0.12065 -0.2794)
			(end 0.12065 -0.2794)
			(stroke
				(width 0.1)
				(type default)
			)
			(layer "F.Fab")
		)
		(fp_line
			(start 0.12065 -0.2794)
			(end 0.12065 -0.3048)
			(stroke
				(width 0.1)
				(type default)
			)
			(layer "F.Fab")
		)
		(fp_line
			(start 0.12065 -0.3048)
			(end 0.67945 -0.3048)
			(stroke
				(width 0.1)
				(type default)
			)
			(layer "F.Fab")
		)
		(fp_line
			(start 0.67945 -0.3048)
			(end 0.67945 0.3048)
			(stroke
				(width 0.1)
				(type default)
			)
			(layer "F.Fab")
		)
		(fp_line
			(start -0.67945 -0.305054)
			(end -0.12065 -0.305054)
			(stroke
				(width 0.1)
				(type default)
			)
			(layer "F.Fab")
		)
		(fp_line
			(start -0.12065 -0.305054)
			(end -0.12065 -0.2794)
			(stroke
				(width 0.1)
				(type default)
			)
			(layer "F.Fab")
		)
		(pad "1" smd circle
			(at -0.40005 0 270)
			(size 0 0)
			(layers "F.Cu" "F.Mask" "F.Paste")
			(net "HP_NIC4_EN")
		)
		(pad "2" smd circle
			(at 0.40005 0 270)
			(size 0 0)
			(layers "F.Cu" "F.Mask" "F.Paste")
			(net "P3V3_NIC4_CO_EN")
		)
	)
	(footprint ""
		(layer "F.Cu")
		(at 125.546612 -154.256994)
		(property "Reference" "PC630"
			(at 0 0 0)
			(layer "F.SilkS")
			(hide yes)
			(effects
				(font
					(size 1.27 1.27)
				)
			)
		)
		(property "Value" ""
			(at 0 0 0)
			(layer "F.Fab")
			(effects
				(font
					(size 1.27 1.27)
				)
			)
		)
		(duplicate_pad_numbers_are_jumpers no)
		(fp_line
			(start -1.2954 -0.5842)
			(end 1.2954 -0.5842)
			(stroke
				(width 0.1524)
				(type default)
			)
			(layer "F.SilkS")
		)
		(fp_line
			(start -1.2954 0.5842)
			(end -1.2954 -0.5842)
			(stroke
				(width 0.1524)
				(type default)
			)
			(layer "F.SilkS")
		)
		(fp_line
			(start 1.2954 -0.5842)
			(end 1.2954 0.5842)
			(stroke
				(width 0.1524)
				(type default)
			)
			(layer "F.SilkS")
		)
		(fp_line
			(start 1.2954 0.5842)
			(end -1.2954 0.5842)
			(stroke
				(width 0.1524)
				(type default)
			)
			(layer "F.SilkS")
		)
		(fp_line
			(start -1.1938 -0.4064)
			(end -0.8636 -0.4064)
			(stroke
				(width 0.1)
				(type default)
			)
			(layer "F.Fab")
		)
		(fp_line
			(start -1.1938 0.4064)
			(end -1.1938 -0.4064)
			(stroke
				(width 0.1)
				(type default)
			)
			(layer "F.Fab")
		)
		(fp_line
			(start -0.8636 -0.4572)
			(end 0.8636 -0.4572)
			(stroke
				(width 0.1)
				(type default)
			)
			(layer "F.Fab")
		)
		(fp_line
			(start -0.8636 -0.4064)
			(end -0.8636 -0.4572)
			(stroke
				(width 0.1)
				(type default)
			)
			(layer "F.Fab")
		)
		(fp_line
			(start -0.8636 0.4064)
			(end -1.1938 0.4064)
			(stroke
				(width 0.1)
				(type default)
			)
			(layer "F.Fab")
		)
		(fp_line
			(start -0.8636 0.4572)
			(end -0.8636 0.4064)
			(stroke
				(width 0.1)
				(type default)
			)
			(layer "F.Fab")
		)
		(fp_line
			(start 0.8636 -0.4572)
			(end 0.8636 -0.4064)
			(stroke
				(width 0.1)
				(type default)
			)
			(layer "F.Fab")
		)
		(fp_line
			(start 0.8636 -0.4064)
			(end 1.1938 -0.4064)
			(stroke
				(width 0.1)
				(type default)
			)
			(layer "F.Fab")
		)
		(fp_line
			(start 0.8636 0.4064)
			(end 0.8636 0.4572)
			(stroke
				(width 0.1)
				(type default)
			)
			(layer "F.Fab")
		)
		(fp_line
			(start 0.8636 0.4572)
			(end -0.8636 0.4572)
			(stroke
				(width 0.1)
				(type default)
			)
			(layer "F.Fab")
		)
		(fp_line
			(start 1.1938 -0.4064)
			(end 1.1938 0.4064)
			(stroke
				(width 0.1)
				(type default)
			)
			(layer "F.Fab")
		)
		(fp_line
			(start 1.1938 0.4064)
			(end 0.8636 0.4064)
			(stroke
				(width 0.1)
				(type default)
			)
			(layer "F.Fab")
		)
		(pad "1" smd rect
			(at -0.7366 0 270)
			(size 0.7112 0.8128)
			(layers "F.Cu" "F.Mask" "F.Paste")
			(net "GND")
		)
		(pad "2" smd rect
			(at 0.7366 0 270)
			(size 0.7112 0.8128)
			(layers "F.Cu" "F.Mask" "F.Paste")
			(net "P12V_NIC2_CO_AVIN_PD")
		)
	)
)
